# S9S_MB_2U (Grand Teton) — schematic netlist excerpt (pin names and nets, part order shuffled) for the footprints in the layout excerpt that follows; sources: Cadence DE-HDL packaged netlist, KiCad conversion of 03242023_DA0F0TMBIJ0_F0T_Motherboard_J_brd_V01_OCP.brd

PU11_P0_3  ISL99390FRZTR5935  ISL99390FRZ-TR5935 IC  pkg QFN21_6X5XB  page 268
  VOS  = PVCCIN_CPU0_VOS3
  AGND  = GND
  VCC  = PVCCIN_CPU0_VDD3
  PVCC  = PVCCIN_CPU0_PVCC
  PGND1  = GND
  GL1  = NC
  PGND2  = GND
  SW  = SW_PVCCIN_CPU0_SW3
  VIN1  = SW_P12V_PVCCIN_CPU0_FLT
  VIN2  = SW_P12V_PVCCIN_CPU0_FLT
  DNC  = NC
  PHASE  = SW_PVCCIN_CPU0_BOOTR3
  BOOT  = SW_PVCCIN_CPU0_BOOT3
  PWM  = PVCCIN_CPU0_PWM3
  EN  = PVCCIN_CPU0_VDD3
  TOUT_FLT  = PVCCIN_CPU0_ATSEN
  LSET  = PVCCIN_CPU0_LSET3
  IOUT  = PVCCIN_CPU0_IMON3
  REFIN  = PVCCIN_CPU0_VREF
  PGND3  = GND
  GL2  = NC

(kicad_pcb
	(version 20260206)
	(generator "pcbnew")
	(generator_version "10.0")
	(general
		(thickness 1.6)
		(legacy_teardrops no)
	)
	(paper "A4")
	(title_block
		(title "03242023_DA0F0TMBIJ0_F0T_Motherboard_J_brd_V01_OCP.brd")
		(comment 1 "Grand Teton / footprints 4017-4017 of 6105")
	)
	(layers
		(0 "F.Cu" signal "TOP")
		(4 "In1.Cu" signal "GND")
		(6 "In2.Cu" signal "IN1")
		(8 "In3.Cu" signal "GND1")
		(10 "In4.Cu" signal "IN2")
		(12 "In5.Cu" signal "GND2")
		(14 "In6.Cu" signal "IN3")
		(16 "In7.Cu" signal "GND3")
		(18 "In8.Cu" signal "VCC")
		(20 "In9.Cu" signal "VCC1")
		(22 "In10.Cu" signal "GND4")
		(24 "In11.Cu" signal "IN4")
		(26 "In12.Cu" signal "GND5")
		(28 "In13.Cu" signal "IN5")
		(30 "In14.Cu" signal "GND6")
		(32 "In15.Cu" signal "IN6")
		(34 "In16.Cu" signal "GND7")
		(2 "B.Cu" signal "BOTTOM")
		(9 "F.Adhes" user "F.Adhesive")
		(11 "B.Adhes" user "B.Adhesive")
		(13 "F.Paste" user "Package Geometry/Pastemask Top")
		(15 "B.Paste" user "Package Geometry/Pastemask Bottom")
		(5 "F.SilkS" user "Ref Des/Silkscreen Top")
		(7 "B.SilkS" user "Ref Des/Silkscreen Bottom")
		(1 "F.Mask" user "Board Geometry/Soldermask Top")
		(3 "B.Mask" user "Board Geometry/Soldermask Bottom")
		(17 "Dwgs.User" user "User.Drawings")
		(19 "Cmts.User" user "User.Comments")
		(21 "Eco1.User" user "User.Eco1")
		(23 "Eco2.User" user "User.Eco2")
		(25 "Edge.Cuts" user "Board Geometry/Outline")
		(27 "Margin" user)
		(31 "F.CrtYd" user "Package Geometry/Place Bound Top")
		(29 "B.CrtYd" user "Package Geometry/Place Bound Bottom")
		(35 "F.Fab" user "Ref Des/Assembly Top")
		(33 "B.Fab" user "Ref Des/Assembly Bottom")
	)
	(footprint ""
		(layer "F.Cu")
		(at 361.258612 -333.716122)
		(property "Reference" "PU11_P0_3"
			(at -2.211832 -6.254496 0)
			(unlocked yes)
			(layer "F.SilkS")
			(effects
				(font
					(size 0.7874 0.5842)
					(thickness 0.1524)
				)
				(justify left)
			)
		)
		(property "Value" ""
			(at 0 0 0)
			(layer "F.Fab")
			(effects
				(font
					(size 1.27 1.27)
				)
			)
		)
		(duplicate_pad_numbers_are_jumpers no)
		(fp_line
			(start -2.500122 -2.999994)
			(end -2.24409 -2.999994)
			(stroke
				(width 0.1524)
				(type default)
			)
			(layer "F.SilkS")
		)
		(fp_line
			(start -2.500122 -2.529078)
			(end -2.500122 -2.999994)
			(stroke
				(width 0.1524)
				(type default)
			)
			(layer "F.SilkS")
		)
		(fp_line
			(start -2.500122 0.6604)
			(end -2.500122 0.229108)
			(stroke
				(width 0.1524)
				(type default)
			)
			(layer "F.SilkS")
		)
		(fp_line
			(start -2.500122 2.999994)
			(end -2.500122 2.339594)
			(stroke
				(width 0.1524)
				(type default)
			)
			(layer "F.SilkS")
		)
		(fp_line
			(start -2.2987 2.999994)
			(end -2.500122 2.999994)
			(stroke
				(width 0.1524)
				(type default)
			)
			(layer "F.SilkS")
		)
		(fp_line
			(start 2.31394 -2.999994)
			(end 2.500122 -2.999994)
			(stroke
				(width 0.1524)
				(type default)
			)
			(layer "F.SilkS")
		)
		(fp_line
			(start 2.500122 -2.999994)
			(end 2.500122 -2.44348)
			(stroke
				(width 0.1524)
				(type default)
			)
			(layer "F.SilkS")
		)
		(fp_line
			(start 2.500122 2.339594)
			(end 2.500122 2.999994)
			(stroke
				(width 0.1524)
				(type default)
			)
			(layer "F.SilkS")
		)
		(fp_line
			(start 2.500122 2.999994)
			(end 2.2987 2.999994)
			(stroke
				(width 0.1524)
				(type default)
			)
			(layer "F.SilkS")
		)
		(fp_poly
			(pts
				(xy -2.2479 -3.591306) (xy -2.7559 -2.575306) (xy -3.2639 -3.591306)
			)
			(stroke
				(width 0)
				(type default)
			)
			(fill yes)
			(layer "F.SilkS")
		)
		(fp_line
			(start -2.500122 -2.999994)
			(end 2.500122 -2.999994)
			(stroke
				(width 0.1)
				(type default)
			)
			(layer "F.Fab")
		)
		(fp_line
			(start -2.500122 2.999994)
			(end -2.500122 -2.999994)
			(stroke
				(width 0.1)
				(type default)
			)
			(layer "F.Fab")
		)
		(fp_line
			(start 2.500122 -2.999994)
			(end 2.500122 2.999994)
			(stroke
				(width 0.1)
				(type default)
			)
			(layer "F.Fab")
		)
		(fp_line
			(start 2.500122 2.999994)
			(end -2.500122 2.999994)
			(stroke
				(width 0.1)
				(type default)
			)
			(layer "F.Fab")
		)
		(fp_poly
			(pts
				(xy -4.218432 -2.783078) (xy -4.218432 -1.767078) (xy -3.202432 -2.275078)
			)
			(stroke
				(width 0)
				(type default)
			)
			(fill yes)
			(layer "F.Fab")
		)
		(pad "1" smd rect
			(at -2.400046 -2.275078 90)
			(size 0.2286 0.6096)
			(layers "F.Cu" "F.Mask" "F.Paste")
			(net "PVCCIN_CPU0_VOS3")
		)
		(pad "2" smd rect
			(at -2.400046 -1.82499 90)
			(size 0.2286 0.6096)
			(layers "F.Cu" "F.Mask" "F.Paste")
			(net "GND")
		)
		(pad "3" smd rect
			(at -2.400046 -1.374902 90)
			(size 0.2286 0.6096)
			(layers "F.Cu" "F.Mask" "F.Paste")
			(net "PVCCIN_CPU0_VDD3")
		)
		(pad "4" smd rect
			(at -2.400046 -0.925068 90)
			(size 0.2286 0.6096)
			(layers "F.Cu" "F.Mask" "F.Paste")
			(net "PVCCIN_CPU0_PVCC")
		)
		(pad "5" smd rect
			(at -2.400046 -0.47498 90)
			(size 0.2286 0.6096)
			(layers "F.Cu" "F.Mask" "F.Paste")
			(net "GND")
		)
		(pad "6" smd rect
			(at -2.400046 -0.024892 90)
			(size 0.2286 0.6096)
			(layers "F.Cu" "F.Mask" "F.Paste")
			(net "Net_8550")
		)
		(pad "7_9-20_24" smd circle
			(at 0 1.150112 90)
			(size 0 0)
			(layers "F.Cu" "F.Mask" "F.Paste")
			(net "GND")
		)
		(pad "10_19" smd rect
			(at 0 2.899918 90)
			(size 0.6096 4.318)
			(layers "F.Cu" "F.Mask" "F.Paste")
			(net "SW_PVCCIN_CPU0_SW3")
		)
		(pad "25_29" smd rect
			(at 1.549908 -1.279906 270)
			(size 2.0574 2.3114)
			(layers "F.Cu" "F.Mask" "F.Paste")
			(net "SW_P12V_PVCCIN_CPU0_FLT")
		)
		(pad "30" smd rect
			(at 2.05994 -2.899918)
			(size 0.2286 0.6096)
			(layers "F.Cu" "F.Mask" "F.Paste")
			(net "SW_P12V_PVCCIN_CPU0_FLT")
		)
		(pad "31" smd rect
			(at 1.610106 -2.899918)
			(size 0.2286 0.6096)
			(layers "F.Cu" "F.Mask" "F.Paste")
			(net "Net_8551")
		)
		(pad "32" smd rect
			(at 1.160018 -2.899918)
			(size 0.2286 0.6096)
			(layers "F.Cu" "F.Mask" "F.Paste")
			(net "SW_PVCCIN_CPU0_BOOTR3")
		)
		(pad "33" smd rect
			(at 0.70993 -2.899918)
			(size 0.2286 0.6096)
			(layers "F.Cu" "F.Mask" "F.Paste")
			(net "SW_PVCCIN_CPU0_BOOT3")
		)
		(pad "34" smd rect
			(at 0.260096 -2.899918)
			(size 0.2286 0.6096)
			(layers "F.Cu" "F.Mask" "F.Paste")
			(net "PVCCIN_CPU0_PWM3")
		)
		(pad "35" smd rect
			(at -0.189992 -2.899918)
			(size 0.2286 0.6096)
			(layers "F.Cu" "F.Mask" "F.Paste")
			(net "PVCCIN_CPU0_VDD3")
		)
		(pad "36" smd rect
			(at -0.64008 -2.899918)
			(size 0.2286 0.6096)
			(layers "F.Cu" "F.Mask" "F.Paste")
			(net "PVCCIN_CPU0_ATSEN")
		)
		(pad "37" smd rect
			(at -1.089914 -2.899918)
			(size 0.2286 0.6096)
			(layers "F.Cu" "F.Mask" "F.Paste")
			(net "PVCCIN_CPU0_LSET3")
		)
		(pad "38" smd rect
			(at -1.540002 -2.899918)
			(size 0.2286 0.6096)
			(layers "F.Cu" "F.Mask" "F.Paste")
			(net "PVCCIN_CPU0_IMON3")
		)
		(pad "39" smd rect
			(at -1.99009 -2.899918)
			(size 0.2286 0.6096)
			(layers "F.Cu" "F.Mask" "F.Paste")
			(net "PVCCIN_CPU0_VREF")
		)
		(pad "40" smd rect
			(at -0.87503 -1.27508)
			(size 1.7526 1.9558)
			(layers "F.Cu" "F.Mask" "F.Paste")
			(net "GND")
		)
		(pad "41" smd rect
			(at -1.525016 0.249936 270)
			(size 0.3048 0.4572)
			(layers "F.Cu" "F.Mask" "F.Paste")
			(net "Net_8549")
		)
		(zone
			(layer "F.Cu")
			(hatch none 0.5)
			(connect_pads
				(clearance 0)
			)
			(min_thickness 0.25)
			(keepout
				(tracks not_allowed)
				(vias allowed)
				(pads allowed)
				(copperpour not_allowed)
				(footprints allowed)
			)
			(placement
				(enabled no)
				(sheetname "")
			)
			(fill
				(thermal_gap 0.5)
				(thermal_bridge_width 0.5)
				(island_removal_mode 0)
			)
			(polygon
				(pts
					(xy 358.75849 -330.716128) (xy 358.75849 -331.465428) (xy 363.758734 -331.465428) (xy 363.758734 -330.716128)
					(xy 363.468412 -330.716128) (xy 363.468412 -331.171804) (xy 359.048812 -331.171804) (xy 359.048812 -330.716128)
				)
			)
		)
		(zone
			(layer "F.Cu")
			(hatch none 0.5)
			(connect_pads
				(clearance 0)
			)
			(min_thickness 0.25)
			(keepout
				(tracks not_allowed)
				(vias allowed)
				(pads allowed)
				(copperpour not_allowed)
				(footprints allowed)
			)
			(placement
				(enabled no)
				(sheetname "")
			)
			(fill
				(thermal_gap 0.5)
				(thermal_bridge_width 0.5)
				(island_removal_mode 0)
			)
			(polygon
				(pts
					(xy 359.214166 -334.028288) (xy 359.456482 -334.028288) (xy 359.456482 -333.962502) (xy 360.09072 -333.962502)
					(xy 360.09072 -333.647288) (xy 360.30789 -333.647288) (xy 360.30789 -332.966822) (xy 358.75849 -332.966822)
					(xy 358.75849 -333.423514) (xy 359.454196 -333.423514) (xy 359.454196 -333.262986) (xy 360.012996 -333.262986)
					(xy 360.012996 -333.669386) (xy 359.454196 -333.669386) (xy 359.454196 -333.448914) (xy 358.75849 -333.448914)
					(xy 358.75849 -333.575914) (xy 359.214166 -333.575914)
				)
			)
		)
	)
)
